# T6G (Grand Teton) — schematic netlist excerpt (pin names and nets, part order shuffled) for the footprints in the layout excerpt that follows; sources: Cadence DE-HDL packaged netlist, KiCad conversion of 04192023_DAF0TMB3IC0_F0TG_MB_C_brd_V02_OCP.brd

R844  Q_RES  4.7K 5% EMPTY  pkg 0201LF  page 185 : A = P1V8_AUX ; B = RT_ROM_SMB_MUX_ADDR0
C643  Q_CAP  1UF 4V 20% X6S  pkg 0201  page 290 : A = P0V9_CPU0_RT1_2A ; B = GND
R6771  Q_RES  4.7K 5% EMPTY  pkg 0201LF  page 184 : A = P1V8_AUX ; B = RT_SMB_MUX_ADDR1
R5004  Q_RES  10K 1% CHIP  pkg 0402LF  page 161 : A = SMB_APML_CPU1_R_SDA ; B = GND

(kicad_pcb
	(version 20260206)
	(generator "pcbnew")
	(generator_version "10.0")
	(general
		(thickness 1.6)
		(legacy_teardrops no)
	)
	(paper "A4")
	(title_block
		(title "04192023_DAF0TMB3IC0_F0TG_MB_C_brd_V02_OCP.brd")
		(comment 1 "Grand Teton / footprints 8300-8303 of 8354")
	)
	(layers
		(0 "F.Cu" signal "TOP")
		(4 "In1.Cu" signal "GND")
		(6 "In2.Cu" signal "IN1")
		(8 "In3.Cu" signal "GND1")
		(10 "In4.Cu" signal "IN2")
		(12 "In5.Cu" signal "GND2")
		(14 "In6.Cu" signal "IN3")
		(16 "In7.Cu" signal "GND3")
		(18 "In8.Cu" signal "VCC")
		(20 "In9.Cu" signal "VCC1")
		(22 "In10.Cu" signal "GND4")
		(24 "In11.Cu" signal "IN4")
		(26 "In12.Cu" signal "GND5")
		(28 "In13.Cu" signal "IN5")
		(30 "In14.Cu" signal "GND6")
		(32 "In15.Cu" signal "IN6")
		(34 "In16.Cu" signal "GND7")
		(2 "B.Cu" signal "BOTTOM")
		(9 "F.Adhes" user "F.Adhesive")
		(11 "B.Adhes" user "B.Adhesive")
		(13 "F.Paste" user "Package Geometry/Pastemask Top")
		(15 "B.Paste" user "Package Geometry/Pastemask Bottom")
		(5 "F.SilkS" user "Ref Des/Silkscreen Top")
		(7 "B.SilkS" user "Ref Des/Silkscreen Bottom")
		(1 "F.Mask" user "Board Geometry/Soldermask Top")
		(3 "B.Mask" user "Board Geometry/Soldermask Bottom")
		(17 "Dwgs.User" user "User.Drawings")
		(19 "Cmts.User" user "User.Comments")
		(21 "Eco1.User" user "User.Eco1")
		(23 "Eco2.User" user "User.Eco2")
		(25 "Edge.Cuts" user "Board Geometry/Outline")
		(27 "Margin" user)
		(31 "F.CrtYd" user "Package Geometry/Place Bound Top")
		(29 "B.CrtYd" user "Package Geometry/Place Bound Bottom")
		(35 "F.Fab" user "Ref Des/Assembly Top")
		(33 "B.Fab" user "Ref Des/Assembly Bottom")
	)
	(footprint ""
		(layer "B.Cu")
		(at 229.87 -232.156 90)
		(property "Reference" "R5004"
			(at 0 0 90)
			(layer "B.SilkS")
			(hide yes)
			(effects
				(font
					(size 1.27 1.27)
				)
				(justify mirror)
			)
		)
		(property "Value" ""
			(at 0 0 90)
			(layer "B.Fab")
			(effects
				(font
					(size 1.27 1.27)
				)
				(justify mirror)
			)
		)
		(duplicate_pad_numbers_are_jumpers no)
		(fp_line
			(start 0.7874 -0.4064)
			(end -0.7874 -0.4064)
			(stroke
				(width 0.1524)
				(type default)
			)
			(layer "B.SilkS")
		)
		(fp_line
			(start -0.7874 -0.4064)
			(end -0.7874 0.4064)
			(stroke
				(width 0.1524)
				(type default)
			)
			(layer "B.SilkS")
		)
		(fp_line
			(start 0.7874 0.4064)
			(end 0.7874 -0.4064)
			(stroke
				(width 0.1524)
				(type default)
			)
			(layer "B.SilkS")
		)
		(fp_line
			(start -0.7874 0.4064)
			(end 0.7874 0.4064)
			(stroke
				(width 0.1524)
				(type default)
			)
			(layer "B.SilkS")
		)
		(fp_line
			(start 0.67945 -0.305054)
			(end 0.12065 -0.305054)
			(stroke
				(width 0.1)
				(type default)
			)
			(layer "B.Fab")
		)
		(fp_line
			(start 0.12065 -0.305054)
			(end 0.12065 -0.2794)
			(stroke
				(width 0.1)
				(type default)
			)
			(layer "B.Fab")
		)
		(fp_line
			(start -0.12065 -0.3048)
			(end -0.67945 -0.3048)
			(stroke
				(width 0.1)
				(type default)
			)
			(layer "B.Fab")
		)
		(fp_line
			(start -0.67945 -0.3048)
			(end -0.67945 0.3048)
			(stroke
				(width 0.1)
				(type default)
			)
			(layer "B.Fab")
		)
		(fp_line
			(start 0.12065 -0.2794)
			(end -0.12065 -0.2794)
			(stroke
				(width 0.1)
				(type default)
			)
			(layer "B.Fab")
		)
		(fp_line
			(start -0.12065 -0.2794)
			(end -0.12065 -0.3048)
			(stroke
				(width 0.1)
				(type default)
			)
			(layer "B.Fab")
		)
		(fp_line
			(start 0.12065 0.2794)
			(end 0.12065 0.3048)
			(stroke
				(width 0.1)
				(type default)
			)
			(layer "B.Fab")
		)
		(fp_line
			(start -0.120396 0.2794)
			(end 0.12065 0.2794)
			(stroke
				(width 0.1)
				(type default)
			)
			(layer "B.Fab")
		)
		(fp_line
			(start 0.67945 0.3048)
			(end 0.67945 -0.305054)
			(stroke
				(width 0.1)
				(type default)
			)
			(layer "B.Fab")
		)
		(fp_line
			(start 0.12065 0.3048)
			(end 0.67945 0.3048)
			(stroke
				(width 0.1)
				(type default)
			)
			(layer "B.Fab")
		)
		(fp_line
			(start -0.120396 0.3048)
			(end -0.120396 0.2794)
			(stroke
				(width 0.1)
				(type default)
			)
			(layer "B.Fab")
		)
		(fp_line
			(start -0.67945 0.3048)
			(end -0.120396 0.3048)
			(stroke
				(width 0.1)
				(type default)
			)
			(layer "B.Fab")
		)
		(pad "1" smd circle
			(at 0.40005 0 270)
			(size 0 0)
			(layers "B.Cu" "B.Mask" "B.Paste")
			(net "SMB_APML_CPU1_R_SDA")
		)
		(pad "2" smd circle
			(at -0.40005 0 270)
			(size 0 0)
			(layers "B.Cu" "B.Mask" "B.Paste")
			(net "GND")
		)
	)
	(footprint ""
		(layer "B.Cu")
		(at 217.17 -331.724 180)
		(property "Reference" "R6771"
			(at 0 0 0)
			(layer "B.SilkS")
			(hide yes)
			(effects
				(font
					(size 1.27 1.27)
				)
				(justify mirror)
			)
		)
		(property "Value" ""
			(at 0 0 0)
			(layer "B.Fab")
			(effects
				(font
					(size 1.27 1.27)
				)
				(justify mirror)
			)
		)
		(duplicate_pad_numbers_are_jumpers no)
		(fp_line
			(start 0.32512 0.175006)
			(end 0.32512 -0.175006)
			(stroke
				(width 0.1)
				(type default)
			)
			(layer "B.Fab")
		)
		(fp_line
			(start 0.32512 -0.175006)
			(end -0.32512 -0.175006)
			(stroke
				(width 0.1)
				(type default)
			)
			(layer "B.Fab")
		)
		(fp_line
			(start -0.32512 0.175006)
			(end 0.32512 0.175006)
			(stroke
				(width 0.1)
				(type default)
			)
			(layer "B.Fab")
		)
		(fp_line
			(start -0.32512 -0.175006)
			(end -0.32512 0.175006)
			(stroke
				(width 0.1)
				(type default)
			)
			(layer "B.Fab")
		)
		(pad "1" smd rect
			(at 0.2667 0)
			(size 0.3048 0.381)
			(layers "B.Cu" "B.Mask" "B.Paste")
			(net "P1V8_AUX")
		)
		(pad "2" smd rect
			(at -0.2667 0 180)
			(size 0.3048 0.381)
			(layers "B.Cu" "B.Mask" "B.Paste")
			(net "RT_SMB_MUX_ADDR1")
		)
	)
	(footprint ""
		(layer "B.Cu")
		(at 241.140488 -330.581 180)
		(property "Reference" "R844"
			(at 0 0 0)
			(layer "B.SilkS")
			(hide yes)
			(effects
				(font
					(size 1.27 1.27)
				)
				(justify mirror)
			)
		)
		(property "Value" ""
			(at 0 0 0)
			(layer "B.Fab")
			(effects
				(font
					(size 1.27 1.27)
				)
				(justify mirror)
			)
		)
		(duplicate_pad_numbers_are_jumpers no)
		(fp_line
			(start 0.32512 0.175006)
			(end 0.32512 -0.175006)
			(stroke
				(width 0.1)
				(type default)
			)
			(layer "B.Fab")
		)
		(fp_line
			(start 0.32512 -0.175006)
			(end -0.32512 -0.175006)
			(stroke
				(width 0.1)
				(type default)
			)
			(layer "B.Fab")
		)
		(fp_line
			(start -0.32512 0.175006)
			(end 0.32512 0.175006)
			(stroke
				(width 0.1)
				(type default)
			)
			(layer "B.Fab")
		)
		(fp_line
			(start -0.32512 -0.175006)
			(end -0.32512 0.175006)
			(stroke
				(width 0.1)
				(type default)
			)
			(layer "B.Fab")
		)
		(pad "1" smd rect
			(at 0.2667 0)
			(size 0.3048 0.381)
			(layers "B.Cu" "B.Mask" "B.Paste")
			(net "P1V8_AUX")
		)
		(pad "2" smd rect
			(at -0.2667 0 180)
			(size 0.3048 0.381)
			(layers "B.Cu" "B.Mask" "B.Paste")
			(net "RT_ROM_SMB_MUX_ADDR0")
		)
	)
	(footprint ""
		(layer "B.Cu")
		(at 352.706178 -395.148562 90)
		(property "Reference" "C643"
			(at 0 0 90)
			(layer "B.SilkS")
			(hide yes)
			(effects
				(font
					(size 1.27 1.27)
				)
				(justify mirror)
			)
		)
		(property "Value" ""
			(at 0 0 90)
			(layer "B.Fab")
			(effects
				(font
					(size 1.27 1.27)
				)
				(justify mirror)
			)
		)
		(duplicate_pad_numbers_are_jumpers no)
		(fp_line
			(start 0.299974 -0.150114)
			(end -0.299974 -0.150114)
			(stroke
				(width 0.1)
				(type default)
			)
			(layer "B.Fab")
		)
		(fp_line
			(start -0.299974 -0.150114)
			(end -0.299974 0.150114)
			(stroke
				(width 0.1)
				(type default)
			)
			(layer "B.Fab")
		)
		(fp_line
			(start 0.299974 0.150114)
			(end 0.299974 -0.150114)
			(stroke
				(width 0.1)
				(type default)
			)
			(layer "B.Fab")
		)
		(fp_line
			(start -0.299974 0.150114)
			(end 0.299974 0.150114)
			(stroke
				(width 0.1)
				(type default)
			)
			(layer "B.Fab")
		)
		(pad "1" smd rect
			(at 0.2667 0 270)
			(size 0.3048 0.381)
			(layers "B.Cu" "B.Mask" "B.Paste")
			(net "P0V9_CPU0_RT1_2A")
		)
		(pad "2" smd rect
			(at -0.2667 0 270)
			(size 0.3048 0.381)
			(layers "B.Cu" "B.Mask" "B.Paste")
			(net "GND")
		)
	)
)
